(kicad_pcb
	(version 20241229)
	(generator "pcbnew")
	(generator_version "9.0")
	(general
		(thickness 1.62)
		(legacy_teardrops no)
	)
	(paper "A3")
	(title_block
		(title "COM Express 7 Baseboard")
		(date "2025-02-04")
		(rev "1.1.2")
		(company "Antmicro Ltd")
		(comment 1 "www.antmicro.com")
		(comment 9 "footprints 154-154 of 802")
	)
	(layers
		(0 "F.Cu" signal)
		(4 "In1.Cu" signal)
		(6 "In2.Cu" signal)
		(8 "In3.Cu" signal)
		(10 "In4.Cu" signal)
		(12 "In5.Cu" signal)
		(14 "In6.Cu" signal)
		(2 "B.Cu" signal)
		(9 "F.Adhes" user "F.Adhesive")
		(11 "B.Adhes" user "B.Adhesive")
		(13 "F.Paste" user)
		(15 "B.Paste" user)
		(5 "F.SilkS" user "F.Silkscreen")
		(7 "B.SilkS" user "B.Silkscreen")
		(1 "F.Mask" user)
		(3 "B.Mask" user)
		(17 "Dwgs.User" user "User.Drawings")
		(19 "Cmts.User" user "User.Comments")
		(21 "Eco1.User" user "User.Eco1")
		(23 "Eco2.User" user "User.Eco2")
		(25 "Edge.Cuts" user)
		(27 "Margin" user)
		(31 "F.CrtYd" user "F.Courtyard")
		(29 "B.CrtYd" user "B.Courtyard")
		(35 "F.Fab" user)
		(33 "B.Fab" user)
	)
	(footprint "antmicro-footprints:QFN-24-1EP_4x4mm_P0.5_EP2.1x2.1mm"
		(layer "F.Cu")
		(at 159.3 160.61)
		(property "Reference" "U5"
			(at 0.699 3.437 0)
			(layer "F.SilkS")
			(effects
				(font
					(size 0.7 0.7)
					(thickness 0.15)
				)
				(justify left bottom)
			)
		)
		(property "Value" "PCA9539AHF"
			(at 0 3.4 0)
			(layer "F.Fab")
			(effects
				(font
					(size 0.7 0.7)
					(thickness 0.15)
				)
				(justify left bottom)
			)
		)
		(property "Datasheet" "https://www.nxp.com/docs/en/data-sheet/PCA9539A.pdf"
			(at 0 0 0)
			(layer "F.Fab")
			(hide yes)
			(effects
				(font
					(size 1.27 1.27)
					(thickness 0.15)
				)
			)
		)
		(property "Author" "Antmicro"
			(at 0 0 0)
			(layer "F.Fab")
			(hide yes)
			(effects
				(font
					(size 1 1)
					(thickness 0.15)
				)
			)
		)
		(property "License" "Apache-2.0"
			(at 0 0 0)
			(layer "F.Fab")
			(hide yes)
			(effects
				(font
					(size 1 1)
					(thickness 0.15)
				)
			)
		)
		(property "MPN" "PCA9539AHF,128"
			(at 0 0 0)
			(layer "F.Fab")
			(hide yes)
			(effects
				(font
					(size 1 1)
					(thickness 0.15)
				)
			)
		)
		(property "Manufacturer" "NXP"
			(at 0 0 0)
			(layer "F.Fab")
			(hide yes)
			(effects
				(font
					(size 1 1)
					(thickness 0.15)
				)
			)
		)
		(property ki_fp_filters "VFQFN-16-1EP_3x3mm")
		(sheetname "2xSFP+")
		(sheetfile "2xSFP+.kicad_sch")
		(attr smd)
		(fp_line
			(start -2.11 -1.636)
			(end -2.11 -2.11)
			(stroke
				(width 0.15)
				(type solid)
			)
			(layer "F.SilkS")
		)
		(fp_line
			(start -2.11 2.108)
			(end -2.11 1.634)
			(stroke
				(width 0.15)
				(type solid)
			)
			(layer "F.SilkS")
		)
		(fp_line
			(start -1.635 -2.11)
			(end -2.11 -2.11)
			(stroke
				(width 0.15)
				(type solid)
			)
			(layer "F.SilkS")
		)
		(fp_line
			(start -1.635 2.108)
			(end -2.11 2.108)
			(stroke
				(width 0.15)
				(type solid)
			)
			(layer "F.SilkS")
		)
		(fp_line
			(start 1.634 -2.11)
			(end 2.108 -2.11)
			(stroke
				(width 0.15)
				(type solid)
			)
			(layer "F.SilkS")
		)
		(fp_line
			(start 1.634 2.108)
			(end 2.108 2.108)
			(stroke
				(width 0.15)
				(type solid)
			)
			(layer "F.SilkS")
		)
		(fp_line
			(start 2.108 -2.11)
			(end 2.108 -1.635)
			(stroke
				(width 0.15)
				(type solid)
			)
			(layer "F.SilkS")
		)
		(fp_line
			(start 2.108 2.108)
			(end 2.108 1.634)
			(stroke
				(width 0.15)
				(type solid)
			)
			(layer "F.SilkS")
		)
		(fp_circle
			(center -2.3 -2.3)
			(end -2.25 -2.3)
			(stroke
				(width 0.15)
				(type solid)
			)
			(fill yes)
			(layer "F.SilkS")
		)
		(fp_rect
			(start -2.503 -2.503)
			(end 2.5 2.5)
			(stroke
				(width 0.05)
				(type solid)
			)
			(fill no)
			(layer "F.CrtYd")
		)
		(fp_line
			(start -2 -1)
			(end -1 -2)
			(stroke
				(width 0.15)
				(type solid)
			)
			(layer "F.Fab")
		)
		(fp_line
			(start -2 1.999)
			(end -2 -1)
			(stroke
				(width 0.15)
				(type solid)
			)
			(layer "F.Fab")
		)
		(fp_line
			(start -1 -2)
			(end 1.999 -2)
			(stroke
				(width 0.15)
				(type solid)
			)
			(layer "F.Fab")
		)
		(fp_line
			(start 1.999 -2)
			(end 1.999 1.999)
			(stroke
				(width 0.15)
				(type solid)
			)
			(layer "F.Fab")
		)
		(fp_line
			(start 1.999 1.999)
			(end -2 1.999)
			(stroke
				(width 0.15)
				(type solid)
			)
			(layer "F.Fab")
		)
		(pad "" smd roundrect
			(at -0.5 -0.5)
			(size 0.8 0.8)
			(layers "F.Paste")
			(roundrect_rratio 0.238095)
			(teardrops
				(best_length_ratio 0.2)
				(max_length 1)
				(best_width_ratio 0.9)
				(max_width 2)
				(curved_edges yes)
				(filter_ratio 0.9)
				(enabled yes)
				(allow_two_segments yes)
				(prefer_zone_connections yes)
			)
		)
		(pad "" smd roundrect
			(at -0.5 0.5)
			(size 0.8 0.8)
			(layers "F.Paste")
			(roundrect_rratio 0.238095)
			(teardrops
				(best_length_ratio 0.2)
				(max_length 1)
				(best_width_ratio 0.9)
				(max_width 2)
				(curved_edges yes)
				(filter_ratio 0.9)
				(enabled yes)
				(allow_two_segments yes)
				(prefer_zone_connections yes)
			)
		)
		(pad "" smd roundrect
			(at 0.5 -0.5)
			(size 0.8 0.8)
			(layers "F.Paste")
			(roundrect_rratio 0.238095)
			(teardrops
				(best_length_ratio 0.2)
				(max_length 1)
				(best_width_ratio 0.9)
				(max_width 2)
				(curved_edges yes)
				(filter_ratio 0.9)
				(enabled yes)
				(allow_two_segments yes)
				(prefer_zone_connections yes)
			)
		)
		(pad "" smd roundrect
			(at 0.5 0.5)
			(size 0.8 0.8)
			(layers "F.Paste")
			(roundrect_rratio 0.238095)
			(teardrops
				(best_length_ratio 0.2)
				(max_length 1)
				(best_width_ratio 0.9)
				(max_width 2)
				(curved_edges yes)
				(filter_ratio 0.9)
				(enabled yes)
				(allow_two_segments yes)
				(prefer_zone_connections yes)
			)
		)
		(pad "1" smd roundrect
			(at -1.938 -1.25)
			(size 0.825 0.25)
			(layers "F.Cu" "F.Mask" "F.Paste")
			(roundrect_rratio 0.25)
			(net 562 "/2xSFP+/~{LED0_0}")
			(pinfunction "IO0_0")
			(pintype "bidirectional")
			(teardrops
				(best_length_ratio 0.2)
				(max_length 1)
				(best_width_ratio 0.9)
				(max_width 2)
				(curved_edges yes)
				(filter_ratio 0.9)
				(enabled yes)
				(allow_two_segments yes)
				(prefer_zone_connections yes)
			)
		)
		(pad "2" smd roundrect
			(at -1.938 -0.75)
			(size 0.825 0.25)
			(layers "F.Cu" "F.Mask" "F.Paste")
			(roundrect_rratio 0.25)
			(net 563 "/2xSFP+/~{LED0_1}")
			(pinfunction "IO0_1")
			(pintype "bidirectional")
			(teardrops
				(best_length_ratio 0.2)
				(max_length 1)
				(best_width_ratio 0.9)
				(max_width 2)
				(curved_edges yes)
				(filter_ratio 0.9)
				(enabled yes)
				(allow_two_segments yes)
				(prefer_zone_connections yes)
			)
		)
		(pad "3" smd roundrect
			(at -1.938 -0.25)
			(size 0.825 0.25)
			(layers "F.Cu" "F.Mask" "F.Paste")
			(roundrect_rratio 0.25)
			(net 564 "/2xSFP+/~{LED0_2}")
			(pinfunction "IO0_2")
			(pintype "bidirectional")
			(teardrops
				(best_length_ratio 0.2)
				(max_length 1)
				(best_width_ratio 0.9)
				(max_width 2)
				(curved_edges yes)
				(filter_ratio 0.9)
				(enabled yes)
				(allow_two_segments yes)
				(prefer_zone_connections yes)
			)
		)
		(pad "4" smd roundrect
			(at -1.938 0.248)
			(size 0.825 0.25)
			(layers "F.Cu" "F.Mask" "F.Paste")
			(roundrect_rratio 0.25)
			(net 565 "/2xSFP+/~{LED1_0}")
			(pinfunction "IO0_3")
			(pintype "bidirectional")
			(teardrops
				(best_length_ratio 0.2)
				(max_length 1)
				(best_width_ratio 0.9)
				(max_width 2)
				(curved_edges yes)
				(filter_ratio 0.9)
				(enabled yes)
				(allow_two_segments yes)
				(prefer_zone_connections yes)
			)
		)
		(pad "5" smd roundrect
			(at -1.938 0.748)
			(size 0.825 0.25)
			(layers "F.Cu" "F.Mask" "F.Paste")
			(roundrect_rratio 0.25)
			(net 566 "/2xSFP+/~{LED1_1}")
			(pinfunction "IO0_4")
			(pintype "bidirectional")
			(teardrops
				(best_length_ratio 0.2)
				(max_length 1)
				(best_width_ratio 0.9)
				(max_width 2)
				(curved_edges yes)
				(filter_ratio 0.9)
				(enabled yes)
				(allow_two_segments yes)
				(prefer_zone_connections yes)
			)
		)
		(pad "6" smd roundrect
			(at -1.938 1.249)
			(size 0.825 0.25)
			(layers "F.Cu" "F.Mask" "F.Paste")
			(roundrect_rratio 0.25)
			(net 567 "/2xSFP+/~{LED1_2}")
			(pinfunction "IO0_5")
			(pintype "bidirectional")
			(teardrops
				(best_length_ratio 0.2)
				(max_length 1)
				(best_width_ratio 0.9)
				(max_width 2)
				(curved_edges yes)
				(filter_ratio 0.9)
				(enabled yes)
				(allow_two_segments yes)
				(prefer_zone_connections yes)
			)
		)
		(pad "7" smd roundrect
			(at -1.25 1.937)
			(size 0.25 0.825)
			(layers "F.Cu" "F.Mask" "F.Paste")
			(roundrect_rratio 0.25)
			(net 697 "Net-(U5-IO0_6)")
			(pinfunction "IO0_6")
			(pintype "bidirectional")
			(teardrops
				(best_length_ratio 0.2)
				(max_length 1)
				(best_width_ratio 0.9)
				(max_width 2)
				(curved_edges yes)
				(filter_ratio 0.9)
				(enabled yes)
				(allow_two_segments yes)
				(prefer_zone_connections yes)
			)
		)
		(pad "8" smd roundrect
			(at -0.75 1.937)
			(size 0.25 0.825)
			(layers "F.Cu" "F.Mask" "F.Paste")
			(roundrect_rratio 0.25)
			(net 698 "Net-(U5-IO0_7)")
			(pinfunction "IO0_7")
			(pintype "bidirectional")
			(teardrops
				(best_length_ratio 0.2)
				(max_length 1)
				(best_width_ratio 0.9)
				(max_width 2)
				(curved_edges yes)
				(filter_ratio 0.9)
				(enabled yes)
				(allow_two_segments yes)
				(prefer_zone_connections yes)
			)
		)
		(pad "9" smd roundrect
			(at -0.25 1.937)
			(size 0.25 0.825)
			(layers "F.Cu" "F.Mask" "F.Paste")
			(roundrect_rratio 0.25)
			(net 1 "GND")
			(pinfunction "GND")
			(pintype "power_in")
			(teardrops
				(best_length_ratio 0.2)
				(max_length 1)
				(best_width_ratio 0.9)
				(max_width 2)
				(curved_edges yes)
				(filter_ratio 0.9)
				(enabled no)
				(allow_two_segments yes)
				(prefer_zone_connections yes)
			)
		)
		(pad "10" smd roundrect
			(at 0.248 1.937)
			(size 0.25 0.825)
			(layers "F.Cu" "F.Mask" "F.Paste")
			(roundrect_rratio 0.25)
			(net 760 "unconnected-(U5-IO1_0-Pad10)")
			(pinfunction "IO1_0")
			(pintype "bidirectional+no_connect")
			(teardrops
				(best_length_ratio 0.2)
				(max_length 1)
				(best_width_ratio 0.9)
				(max_width 2)
				(curved_edges yes)
				(filter_ratio 0.9)
				(enabled yes)
				(allow_two_segments yes)
				(prefer_zone_connections yes)
			)
		)
		(pad "11" smd roundrect
			(at 0.748 1.937)
			(size 0.25 0.825)
			(layers "F.Cu" "F.Mask" "F.Paste")
			(roundrect_rratio 0.25)
			(net 761 "unconnected-(U5-IO1_1-Pad11)")
			(pinfunction "IO1_1")
			(pintype "bidirectional+no_connect")
			(teardrops
				(best_length_ratio 0.2)
				(max_length 1)
				(best_width_ratio 0.9)
				(max_width 2)
				(curved_edges yes)
				(filter_ratio 0.9)
				(enabled yes)
				(allow_two_segments yes)
				(prefer_zone_connections yes)
			)
		)
		(pad "12" smd roundrect
			(at 1.249 1.937)
			(size 0.25 0.825)
			(layers "F.Cu" "F.Mask" "F.Paste")
			(roundrect_rratio 0.25)
			(net 762 "unconnected-(U5-IO1_2-Pad12)")
			(pinfunction "IO1_2")
			(pintype "bidirectional+no_connect")
			(teardrops
				(best_length_ratio 0.2)
				(max_length 1)
				(best_width_ratio 0.9)
				(max_width 2)
				(curved_edges yes)
				(filter_ratio 0.9)
				(enabled yes)
				(allow_two_segments yes)
				(prefer_zone_connections yes)
			)
		)
		(pad "13" smd roundrect
			(at 1.937 1.249)
			(size 0.825 0.25)
			(layers "F.Cu" "F.Mask" "F.Paste")
			(roundrect_rratio 0.25)
			(net 763 "unconnected-(U5-IO1_3-Pad13)")
			(pinfunction "IO1_3")
			(pintype "bidirectional+no_connect")
			(teardrops
				(best_length_ratio 0.2)
				(max_length 1)
				(best_width_ratio 0.9)
				(max_width 2)
				(curved_edges yes)
				(filter_ratio 0.9)
				(enabled yes)
				(allow_two_segments yes)
				(prefer_zone_connections yes)
			)
		)
		(pad "14" smd roundrect
			(at 1.937 0.748)
			(size 0.825 0.25)
			(layers "F.Cu" "F.Mask" "F.Paste")
			(roundrect_rratio 0.25)
			(net 764 "unconnected-(U5-IO1_4-Pad14)")
			(pinfunction "IO1_4")
			(pintype "bidirectional+no_connect")
			(teardrops
				(best_length_ratio 0.2)
				(max_length 1)
				(best_width_ratio 0.9)
				(max_width 2)
				(curved_edges yes)
				(filter_ratio 0.9)
				(enabled yes)
				(allow_two_segments yes)
				(prefer_zone_connections yes)
			)
		)
		(pad "15" smd roundrect
			(at 1.937 0.248)
			(size 0.825 0.25)
			(layers "F.Cu" "F.Mask" "F.Paste")
			(roundrect_rratio 0.25)
			(net 765 "unconnected-(U5-IO1_5-Pad15)")
			(pinfunction "IO1_5")
			(pintype "bidirectional+no_connect")
			(teardrops
				(best_length_ratio 0.2)
				(max_length 1)
				(best_width_ratio 0.9)
				(max_width 2)
				(curved_edges yes)
				(filter_ratio 0.9)
				(enabled yes)
				(allow_two_segments yes)
				(prefer_zone_connections yes)
			)
		)
		(pad "16" smd roundrect
			(at 1.937 -0.25)
			(size 0.825 0.25)
			(layers "F.Cu" "F.Mask" "F.Paste")
			(roundrect_rratio 0.25)
			(net 766 "unconnected-(U5-IO1_6-Pad16)")
			(pinfunction "IO1_6")
			(pintype "bidirectional+no_connect")
			(teardrops
				(best_length_ratio 0.2)
				(max_length 1)
				(best_width_ratio 0.9)
				(max_width 2)
				(curved_edges yes)
				(filter_ratio 0.9)
				(enabled yes)
				(allow_two_segments yes)
				(prefer_zone_connections yes)
			)
		)
		(pad "17" smd roundrect
			(at 1.937 -0.75)
			(size 0.825 0.25)
			(layers "F.Cu" "F.Mask" "F.Paste")
			(roundrect_rratio 0.25)
			(net 767 "unconnected-(U5-IO1_7-Pad17)")
			(pinfunction "IO1_7")
			(pintype "bidirectional+no_connect")
			(teardrops
				(best_length_ratio 0.2)
				(max_length 1)
				(best_width_ratio 0.9)
				(max_width 2)
				(curved_edges yes)
				(filter_ratio 0.9)
				(enabled yes)
				(allow_two_segments yes)
				(prefer_zone_connections yes)
			)
		)
		(pad "18" smd roundrect
			(at 1.937 -1.25)
			(size 0.825 0.25)
			(layers "F.Cu" "F.Mask" "F.Paste")
			(roundrect_rratio 0.25)
			(net 557 "Net-(U5-A0)")
			(pinfunction "A0")
			(pintype "input")
			(teardrops
				(best_length_ratio 0.2)
				(max_length 1)
				(best_width_ratio 0.9)
				(max_width 2)
				(curved_edges yes)
				(filter_ratio 0.9)
				(enabled yes)
				(allow_two_segments yes)
				(prefer_zone_connections yes)
			)
		)
		(pad "19" smd roundrect
			(at 1.249 -1.938)
			(size 0.25 0.825)
			(layers "F.Cu" "F.Mask" "F.Paste")
			(roundrect_rratio 0.25)
			(net 559 "Net-(U5-SCL)")
			(pinfunction "SCL")
			(pintype "input")
			(teardrops
				(best_length_ratio 0.2)
				(max_length 1)
				(best_width_ratio 0.9)
				(max_width 2)
				(curved_edges yes)
				(filter_ratio 0.9)
				(enabled yes)
				(allow_two_segments yes)
				(prefer_zone_connections yes)
			)
		)
		(pad "20" smd roundrect
			(at 0.748 -1.938)
			(size 0.25 0.825)
			(layers "F.Cu" "F.Mask" "F.Paste")
			(roundrect_rratio 0.25)
			(net 558 "Net-(U5-SDA)")
			(pinfunction "SDA")
			(pintype "bidirectional")
			(teardrops
				(best_length_ratio 0.2)
				(max_length 1)
				(best_width_ratio 0.9)
				(max_width 2)
				(curved_edges yes)
				(filter_ratio 0.9)
				(enabled yes)
				(allow_two_segments yes)
				(prefer_zone_connections yes)
			)
		)
		(pad "21" smd roundrect
			(at 0.248 -1.938)
			(size 0.25 0.825)
			(layers "F.Cu" "F.Mask" "F.Paste")
			(roundrect_rratio 0.25)
			(net 2 "+3V3")
			(pinfunction "VDD")
			(pintype "power_in")
			(teardrops
				(best_length_ratio 0.2)
				(max_length 1)
				(best_width_ratio 0.9)
				(max_width 2)
				(curved_edges yes)
				(filter_ratio 0.9)
				(enabled yes)
				(allow_two_segments yes)
				(prefer_zone_connections yes)
			)
		)
		(pad "22" smd roundrect
			(at -0.25 -1.938)
			(size 0.25 0.825)
			(layers "F.Cu" "F.Mask" "F.Paste")
			(roundrect_rratio 0.25)
			(net 768 "unconnected-(U5-~{INT}-Pad22)")
			(pinfunction "~{INT}")
			(pintype "output+no_connect")
			(teardrops
				(best_length_ratio 0.2)
				(max_length 1)
				(best_width_ratio 0.9)
				(max_width 2)
				(curved_edges yes)
				(filter_ratio 0.9)
				(enabled yes)
				(allow_two_segments yes)
				(prefer_zone_connections yes)
			)
		)
		(pad "23" smd roundrect
			(at -0.75 -1.938)
			(size 0.25 0.825)
			(layers "F.Cu" "F.Mask" "F.Paste")
			(roundrect_rratio 0.25)
			(net 561 "Net-(U5-A1)")
			(pinfunction "A1")
			(pintype "input")
			(teardrops
				(best_length_ratio 0.2)
				(max_length 1)
				(best_width_ratio 0.9)
				(max_width 2)
				(curved_edges yes)
				(filter_ratio 0.9)
				(enabled yes)
				(allow_two_segments yes)
				(prefer_zone_connections yes)
			)
		)
		(pad "24" smd roundrect
			(at -1.25 -1.938)
			(size 0.25 0.825)
			(layers "F.Cu" "F.Mask" "F.Paste")
			(roundrect_rratio 0.25)
			(net 560 "Net-(U5-~{RESET})")
			(pinfunction "~{RESET}")
			(pintype "input")
			(teardrops
				(best_length_ratio 0.2)
				(max_length 1)
				(best_width_ratio 0.9)
				(max_width 2)
				(curved_edges yes)
				(filter_ratio 0.9)
				(enabled yes)
				(allow_two_segments yes)
				(prefer_zone_connections yes)
			)
		)
		(pad "25" smd rect
			(at 0 0)
			(size 2.1 2.1)
			(layers "F.Cu" "F.Mask")
			(net 1 "GND")
			(pinfunction "GND")
			(pintype "passive")
			(teardrops
				(best_length_ratio 0.2)
				(max_length 1)
				(best_width_ratio 0.9)
				(max_width 2)
				(curved_edges yes)
				(filter_ratio 0.9)
				(enabled no)
				(allow_two_segments yes)
				(prefer_zone_connections yes)
			)
		)
	)
)
